(kicad_pcb
	(version 20241229)
	(generator "pcbnew")
	(generator_version "9.0")
	(general
		(thickness 1.6642)
		(legacy_teardrops no)
	)
	(paper "A3")
	(title_block
		(title "PolarFire SoM")
		(date "2025-07-22")
		(rev "1.1.4")
		(company "Antmicro Ltd")
		(comment 1 "www.antmicro.com")
		(comment 9 "footprints 71-73 of 470")
	)
	(layers
		(0 "F.Cu" mixed)
		(4 "In1.Cu" power)
		(6 "In2.Cu" signal)
		(8 "In3.Cu" power)
		(10 "In4.Cu" signal)
		(12 "In5.Cu" power)
		(14 "In6.Cu" power)
		(16 "In7.Cu" signal)
		(18 "In8.Cu" power)
		(20 "In9.Cu" signal)
		(22 "In10.Cu" power)
		(24 "In11.Cu" signal)
		(26 "In12.Cu" signal)
		(2 "B.Cu" mixed)
		(9 "F.Adhes" user "F.Adhesive")
		(11 "B.Adhes" user "B.Adhesive")
		(13 "F.Paste" user)
		(15 "B.Paste" user)
		(5 "F.SilkS" user "F.Silkscreen")
		(7 "B.SilkS" user "B.Silkscreen")
		(1 "F.Mask" user)
		(3 "B.Mask" user)
		(17 "Dwgs.User" user "User.Drawings")
		(19 "Cmts.User" user "User.Comments")
		(21 "Eco1.User" user "User.Eco1")
		(23 "Eco2.User" user "User.Eco2")
		(25 "Edge.Cuts" user)
		(27 "Margin" user)
		(31 "F.CrtYd" user "F.Courtyard")
		(29 "B.CrtYd" user "B.Courtyard")
		(35 "F.Fab" user)
		(33 "B.Fab" user)
	)
	(footprint "antmicro-footprints:TP_SMD_0.75mm"
		(layer "F.Cu")
		(at 198.31 146.86)
		(property "Reference" "TP18"
			(at 0 -0.6 0)
			(layer "F.SilkS")
			(hide yes)
			(effects
				(font
					(size 0.7 0.7)
					(thickness 0.15)
				)
				(justify left bottom)
			)
		)
		(property "Value" "TP_0.75mm_SMD"
			(at 0 1.2 0)
			(layer "F.Fab")
			(hide yes)
			(effects
				(font
					(size 0.7 0.7)
					(thickness 0.15)
				)
				(justify left bottom)
			)
		)
		(property "Description" "SMT test point"
			(at 0 0 0)
			(layer "F.Fab")
			(hide yes)
			(effects
				(font
					(size 1.27 1.27)
					(thickness 0.15)
				)
			)
		)
		(property "Author" "Antmicro"
			(at 0 0 0)
			(layer "F.Fab")
			(hide yes)
			(effects
				(font
					(size 1 1)
					(thickness 0.15)
				)
			)
		)
		(property "License" "Apache-2.0"
			(at 0 0 0)
			(layer "F.Fab")
			(hide yes)
			(effects
				(font
					(size 1 1)
					(thickness 0.15)
				)
			)
		)
		(property "MPN" ""
			(at 0 0 0)
			(layer "F.Fab")
			(hide yes)
			(effects
				(font
					(size 1 1)
					(thickness 0.15)
				)
			)
		)
		(property "Manufacturer" ""
			(at 0 0 0)
			(layer "F.Fab")
			(hide yes)
			(effects
				(font
					(size 1 1)
					(thickness 0.15)
				)
			)
		)
		(property "Public" "False"
			(at 0 0 0)
			(layer "F.Fab")
			(hide yes)
			(effects
				(font
					(size 1 1)
					(thickness 0.15)
				)
			)
		)
		(sheetname "/HDMI/")
		(sheetfile "hdmi.kicad_sch")
		(attr exclude_from_pos_files exclude_from_bom)
		(fp_circle
			(center 0 0)
			(end 0.475 0)
			(stroke
				(width 0.05)
				(type default)
			)
			(fill no)
			(layer "F.CrtYd")
		)
		(fp_text user "${REFERENCE}"
			(at -0.4 2.7 0)
			(layer "F.Fab")
			(effects
				(font
					(size 0.7 0.7)
					(thickness 0.15)
				)
				(justify left bottom)
			)
		)
		(fp_text user "License: Apache-2.0"
			(at -0.4 5.101 0)
			(layer "F.Fab")
			(effects
				(font
					(size 0.7 0.7)
					(thickness 0.15)
				)
				(justify left bottom)
			)
		)
		(fp_text user "Author: Antmicro"
			(at -0.4 3.901 0)
			(layer "F.Fab")
			(effects
				(font
					(size 0.7 0.7)
					(thickness 0.15)
				)
				(justify left bottom)
			)
		)
		(pad "1" smd circle
			(at 0 0)
			(size 0.75 0.75)
			(layers "F.Cu" "F.Mask")
			(net 556 "Net-(U15-OEB)")
			(pinfunction "1")
			(pintype "passive")
		)
	)
	(footprint "antmicro-footprints:C_0402_1005Metric"
		(layer "F.Cu")
		(at 181.734404 153.229531)
		(descr "Capacitor SMD 0402")
		(tags "capacitor SMD 0402")
		(property "Reference" "C96"
			(at -1.814404 2.490469 45)
			(layer "F.SilkS")
			(effects
				(font
					(size 0.7 0.7)
					(thickness 0.15)
				)
				(justify left bottom)
			)
		)
		(property "Value" "C_22n_0402"
			(at -1.022927 2.155213 0)
			(layer "F.Fab")
			(hide yes)
			(effects
				(font
					(size 0.7 0.7)
					(thickness 0.15)
				)
				(justify left bottom)
			)
		)
		(property "Datasheet" "https://www.murata.com/products/productdetail?partno=GCM155R71H223MA55%23"
			(at 0 0 0)
			(layer "F.Fab")
			(hide yes)
			(effects
				(font
					(size 1.27 1.27)
					(thickness 0.15)
				)
			)
		)
		(property "Description" "SMD Multilayer Ceramic Capacitors, 0.022 µF, 50 V, 20%, 0402 [1005 Metric], X7R"
			(at 0 0 0)
			(layer "F.Fab")
			(hide yes)
			(effects
				(font
					(size 1.27 1.27)
					(thickness 0.15)
				)
			)
		)
		(property "Author" "Antmicro"
			(at 0 0 0)
			(layer "F.Fab")
			(hide yes)
			(effects
				(font
					(size 1 1)
					(thickness 0.15)
				)
			)
		)
		(property "Dielectric" ""
			(at 0 0 0)
			(layer "F.Fab")
			(hide yes)
			(effects
				(font
					(size 1 1)
					(thickness 0.15)
				)
			)
		)
		(property "License" "Apache-2.0"
			(at 0 0 0)
			(layer "F.Fab")
			(hide yes)
			(effects
				(font
					(size 1 1)
					(thickness 0.15)
				)
			)
		)
		(property "MPN" "GCM155R71H223MA55D"
			(at 0 0 0)
			(layer "F.Fab")
			(hide yes)
			(effects
				(font
					(size 1 1)
					(thickness 0.15)
				)
			)
		)
		(property "Manufacturer" "Murata"
			(at 0 0 0)
			(layer "F.Fab")
			(hide yes)
			(effects
				(font
					(size 1 1)
					(thickness 0.15)
				)
			)
		)
		(property "Public" ""
			(at 0 0 0)
			(layer "F.Fab")
			(hide yes)
			(effects
				(font
					(size 1 1)
					(thickness 0.15)
				)
			)
		)
		(property "Val" "22n"
			(at 0 0 0)
			(layer "F.Fab")
			(hide yes)
			(effects
				(font
					(size 1 1)
					(thickness 0.15)
				)
			)
		)
		(property "Voltage" ""
			(at 0 0 0)
			(layer "F.Fab")
			(hide yes)
			(effects
				(font
					(size 1 1)
					(thickness 0.15)
				)
			)
		)
		(sheetname "/Supply/")
		(sheetfile "supply.kicad_sch")
		(attr smd)
		(fp_rect
			(start -0.925 -0.47)
			(end 0.925 0.47)
			(stroke
				(width 0.05)
				(type default)
			)
			(fill no)
			(layer "F.CrtYd")
		)
		(fp_line
			(start -0.494 -0.25)
			(end 0.504 -0.25)
			(stroke
				(width 0.15)
				(type solid)
			)
			(layer "F.Fab")
		)
		(fp_line
			(start -0.494 0.248)
			(end -0.494 -0.25)
			(stroke
				(width 0.15)
				(type solid)
			)
			(layer "F.Fab")
		)
		(fp_line
			(start 0.504 -0.25)
			(end 0.504 0.248)
			(stroke
				(width 0.15)
				(type solid)
			)
			(layer "F.Fab")
		)
		(fp_line
			(start 0.504 0.248)
			(end -0.494 0.248)
			(stroke
				(width 0.15)
				(type solid)
			)
			(layer "F.Fab")
		)
		(fp_text user "Author: Antmicro"
			(at -0.939 3.399 0)
			(layer "F.Fab")
			(effects
				(font
					(size 0.7 0.7)
					(thickness 0.15)
				)
				(justify left bottom)
			)
		)
		(fp_text user "${REFERENCE}"
			(at -0.939 4.599 0)
			(layer "F.Fab")
			(effects
				(font
					(size 0.7 0.7)
					(thickness 0.15)
				)
				(justify left bottom)
			)
		)
		(fp_text user "License: Apache-2.0"
			(at -0.939 5.799 0)
			(layer "F.Fab")
			(effects
				(font
					(size 0.7 0.7)
					(thickness 0.15)
				)
				(justify left bottom)
			)
		)
		(pad "1" smd roundrect
			(at -0.48 0)
			(size 0.59 0.64)
			(layers "F.Cu" "F.Mask" "F.Paste")
			(roundrect_rratio 0.25)
			(net 417 "GND")
			(pintype "passive")
		)
		(pad "2" smd roundrect
			(at 0.48 0)
			(size 0.59 0.64)
			(layers "F.Cu" "F.Mask" "F.Paste")
			(roundrect_rratio 0.25)
			(net 228 "/Supply/1V05_SS")
			(pintype "passive")
		)
	)
	(footprint "antmicro-footprints:QFN-26_3.5x4.5x1mm_P0.45mm"
		(layer "F.Cu")
		(at 180.125 141.9425)
		(property "Reference" "U7"
			(at -2.585 3.5575 0)
			(unlocked yes)
			(layer "F.SilkS")
			(effects
				(font
					(size 0.7 0.7)
					(thickness 0.15)
				)
				(justify left bottom)
			)
		)
		(property "Value" "MP5424GRM"
			(at 0 3.7 0)
			(unlocked yes)
			(layer "F.Fab")
			(hide yes)
			(effects
				(font
					(size 0.7 0.7)
					(thickness 0.15)
				)
				(justify left bottom)
			)
		)
		(property "Datasheet" "https://www.monolithicpower.com/en/documentview/productdocument/index/version/2/document_type/Datasheet/lang/en/sku/MP5424GRM/document_id/10311/"
			(at 0 0 0)
			(layer "F.Fab")
			(hide yes)
			(effects
				(font
					(size 1.27 1.27)
					(thickness 0.15)
				)
			)
		)
		(property "Description" "5V PMIC with Four 4.5A/2.5A/4.5A/2A Buck Converters, 3 LDOs, 1 Load Switch and Flexible System Settings via I2C and MTP"
			(at 0 0 0)
			(layer "F.Fab")
			(hide yes)
			(effects
				(font
					(size 1.27 1.27)
					(thickness 0.15)
				)
			)
		)
		(property "Author" "Antmicro"
			(at 0 0 0)
			(layer "F.Fab")
			(hide yes)
			(effects
				(font
					(size 1 1)
					(thickness 0.15)
				)
			)
		)
		(property "License" "Apache-2.0"
			(at 0 0 0)
			(layer "F.Fab")
			(hide yes)
			(effects
				(font
					(size 1 1)
					(thickness 0.15)
				)
			)
		)
		(property "MPN" "MP5424GRM-0000-Z"
			(at 0 0 0)
			(layer "F.Fab")
			(hide yes)
			(effects
				(font
					(size 1 1)
					(thickness 0.15)
				)
			)
		)
		(property "Manufacturer" "Monolithic Power Systems"
			(at 0 0 0)
			(layer "F.Fab")
			(hide yes)
			(effects
				(font
					(size 1 1)
					(thickness 0.15)
				)
			)
		)
		(sheetname "/Supply/")
		(sheetfile "supply.kicad_sch")
		(attr smd)
		(fp_line
			(start -1.8 -2.3)
			(end -1.405 -2.3)
			(stroke
				(width 0.15)
				(type solid)
			)
			(layer "F.SilkS")
		)
		(fp_line
			(start -1.8 2.1)
			(end -1.8 2.3)
			(stroke
				(width 0.15)
				(type solid)
			)
			(layer "F.SilkS")
		)
		(fp_line
			(start -1.407 2.3)
			(end -1.8 2.3)
			(stroke
				(width 0.15)
				(type solid)
			)
			(layer "F.SilkS")
		)
		(fp_line
			(start 1.407 -2.3)
			(end 1.8 -2.3)
			(stroke
				(width 0.15)
				(type solid)
			)
			(layer "F.SilkS")
		)
		(fp_line
			(start 1.8 -2.1)
			(end 1.8 -2.3)
			(stroke
				(width 0.15)
				(type solid)
			)
			(layer "F.SilkS")
		)
		(fp_line
			(start 1.8 2.3)
			(end 1.407 2.3)
			(stroke
				(width 0.15)
				(type solid)
			)
			(layer "F.SilkS")
		)
		(fp_line
			(start 1.8 2.3)
			(end 1.8 2.1)
			(stroke
				(width 0.15)
				(type solid)
			)
			(layer "F.SilkS")
		)
		(fp_circle
			(center -2 -2.15)
			(end -1.95 -2.15)
			(stroke
				(width 0.15)
				(type solid)
			)
			(fill yes)
			(layer "F.SilkS")
		)
		(fp_rect
			(start -2.1 -2.6)
			(end 2.1 2.6)
			(stroke
				(width 0.05)
				(type solid)
			)
			(fill no)
			(layer "F.CrtYd")
		)
		(fp_line
			(start -1.803 -2.304)
			(end -1.803 2.294)
			(stroke
				(width 0.15)
				(type solid)
			)
			(layer "F.Fab")
		)
		(fp_line
			(start -1.803 -1.034)
			(end -0.533 -2.304)
			(stroke
				(width 0.15)
				(type solid)
			)
			(layer "F.Fab")
		)
		(fp_line
			(start -1.803 2.294)
			(end 1.803 2.294)
			(stroke
				(width 0.15)
				(type solid)
			)
			(layer "F.Fab")
		)
		(fp_line
			(start 1.803 -2.304)
			(end -1.803 -2.304)
			(stroke
				(width 0.15)
				(type solid)
			)
			(layer "F.Fab")
		)
		(fp_line
			(start 1.803 2.294)
			(end 1.803 -2.304)
			(stroke
				(width 0.15)
				(type solid)
			)
			(layer "F.Fab")
		)
		(fp_text user "${REFERENCE}"
			(at -2.65 9.595 0)
			(unlocked yes)
			(layer "F.Fab")
			(effects
				(font
					(size 0.7 0.7)
					(thickness 0.15)
				)
				(justify left bottom)
			)
		)
		(fp_text user "Author: Antmicro"
			(at -2.65 8.395 0)
			(layer "F.Fab")
			(effects
				(font
					(size 0.7 0.7)
					(thickness 0.15)
				)
				(justify left bottom)
			)
		)
		(fp_text user "License: Apache-2.0"
			(at -2.65 7.195 0)
			(layer "F.Fab")
			(effects
				(font
					(size 0.7 0.7)
					(thickness 0.15)
				)
				(justify left bottom)
			)
		)
		(pad "1" smd rect
			(at -1.61 -1.855)
			(size 0.875 0.2)
			(layers "F.Cu" "F.Mask" "F.Paste")
			(net 209 "/Supply/SENSE1_P")
			(pinfunction "FB1")
			(pintype "input")
		)
		(pad "1" smd roundrect
			(at -1.29 -1.905 90)
			(size 0.3 0.525)
			(layers "F.Cu" "F.Mask" "F.Paste")
			(roundrect_rratio 0)
			(chamfer_ratio 0.5)
			(chamfer bottom_left)
			(net 209 "/Supply/SENSE1_P")
			(pinfunction "FB1")
			(pintype "input")
		)
		(pad "1" smd rect
			(at -1.125 -2.23 90)
			(size 0.65 0.2)
			(layers "F.Cu" "F.Mask" "F.Paste")
			(net 209 "/Supply/SENSE1_P")
			(pinfunction "FB1")
			(pintype "input")
		)
		(pad "2" smd rect
			(at -1.6 -1.405)
			(size 0.9 0.2)
			(layers "F.Cu" "F.Mask" "F.Paste")
			(net 187 "/Supply/PWRON")
			(pinfunction "PWRON")
			(pintype "input")
		)
		(pad "3" smd rect
			(at -1.4 -0.955)
			(size 1.3 0.2)
			(layers "F.Cu" "F.Mask" "F.Paste")
			(net 90 "+5V")
			(pinfunction "VIN1")
			(pintype "power_in")
		)
		(pad "4" smd rect
			(at -1.4 -0.505)
			(size 1.3 0.2)
			(layers "F.Cu" "F.Mask" "F.Paste")
			(net 168 "Net-(U7-SW1)")
			(pinfunction "SW1")
			(pintype "power_out")
		)
		(pad "5" smd rect
			(at -1.4 -0.005)
			(size 1.3 0.3)
			(layers "F.Cu" "F.Mask" "F.Paste")
			(net 417 "GND")
			(pinfunction "GND")
			(pintype "power_in")
		)
		(pad "6" smd rect
			(at -1.4 0.495)
			(size 1.3 0.2)
			(layers "F.Cu" "F.Mask" "F.Paste")
			(net 181 "Net-(U7-SW3)")
			(pinfunction "SW3")
			(pintype "power_out")
		)
		(pad "7" smd rect
			(at -1.4 0.945)
			(size 1.3 0.2)
			(layers "F.Cu" "F.Mask" "F.Paste")
			(net 90 "+5V")
			(pinfunction "VIN3")
			(pintype "power_in")
		)
		(pad "8" smd rect
			(at -1.6 1.395)
			(size 0.9 0.2)
			(layers "F.Cu" "F.Mask" "F.Paste")
			(net 406 "/Supply/SENSE2_P")
			(pinfunction "FB3")
			(pintype "input")
		)
		(pad "9" smd rect
			(at -1.54 1.845)
			(size 1.025 0.2)
			(layers "F.Cu" "F.Mask" "F.Paste")
			(net 656 "/Supply/PG")
			(pinfunction "RSTO")
			(pintype "input")
		)
		(pad "9" smd rect
			(at -1.29 1.895 90)
			(size 0.3 0.525)
			(layers "F.Cu" "F.Mask" "F.Paste")
			(net 656 "/Supply/PG")
			(pinfunction "RSTO")
			(pintype "input")
		)
		(pad "9" smd rect
			(at -1.125 2.145 90)
			(size 0.8 0.2)
			(layers "F.Cu" "F.Mask" "F.Paste")
			(net 656 "/Supply/PG")
			(pinfunction "RSTO")
			(pintype "input")
		)
		(pad "10" smd rect
			(at -0.675 2.095 90)
			(size 0.9 0.2)
			(layers "F.Cu" "F.Mask" "F.Paste")
			(net 92 "/FPGA MSSIO/SUPPLY.SCL")
			(pinfunction "SCL")
			(pintype "input")
		)
		(pad "11" smd rect
			(at -0.225 2.095 90)
			(size 0.9 0.2)
			(layers "F.Cu" "F.Mask" "F.Paste")
			(net 100 "/FPGA MSSIO/SUPPLY.SDA")
			(pinfunction "SDA")
			(pintype "bidirectional")
		)
		(pad "12" smd rect
			(at 0.225 2.095 90)
			(size 0.9 0.2)
			(layers "F.Cu" "F.Mask" "F.Paste")
			(net 633 "Net-(U7-OUT4)")
			(pinfunction "OUT4")
			(pintype "power_out")
		)
		(pad "13" smd rect
			(at 0.675 2.095 90)
			(size 0.9 0.2)
			(layers "F.Cu" "F.Mask" "F.Paste")
			(net 90 "+5V")
			(pinfunction "VIN5")
			(pintype "power_in")
		)
		(pad "14" smd rect
			(at 1.125 2.145 90)
			(size 0.8 0.2)
			(layers "F.Cu" "F.Mask" "F.Paste")
			(net 634 "Net-(U7-OUT5)")
			(pinfunction "OUT5")
			(pintype "power_out")
		)
		(pad "14" smd rect
			(at 1.29 1.895 90)
			(size 0.3 0.525)
			(layers "F.Cu" "F.Mask" "F.Paste")
			(net 634 "Net-(U7-OUT5)")
			(pinfunction "OUT5")
			(pintype "power_out")
		)
		(pad "14" smd rect
			(at 1.54 1.845)
			(size 1.025 0.2)
			(layers "F.Cu" "F.Mask" "F.Paste")
			(net 634 "Net-(U7-OUT5)")
			(pinfunction "OUT5")
			(pintype "power_out")
		)
		(pad "15" smd rect
			(at 1.6 1.395)
			(size 0.9 0.2)
			(layers "F.Cu" "F.Mask" "F.Paste")
			(net 409 "/Supply/SENSE4_P")
			(pinfunction "FB4")
			(pintype "input")
		)
		(pad "16" smd rect
			(at 1.4 0.945)
			(size 1.3 0.2)
			(layers "F.Cu" "F.Mask" "F.Paste")
			(net 90 "+5V")
			(pinfunction "VIN4")
			(pintype "power_in")
		)
		(pad "17" smd rect
			(at 1.4 0.495)
			(size 1.3 0.2)
			(layers "F.Cu" "F.Mask" "F.Paste")
			(net 184 "Net-(U7-SW4)")
			(pinfunction "SW4")
			(pintype "power_out")
		)
		(pad "18" smd rect
			(at 1.4 -0.005)
			(size 1.3 0.3)
			(layers "F.Cu" "F.Mask" "F.Paste")
			(net 417 "GND")
			(pinfunction "GND")
			(pintype "passive")
		)
		(pad "19" smd rect
			(at 1.4 -0.505)
			(size 1.3 0.2)
			(layers "F.Cu" "F.Mask" "F.Paste")
			(net 175 "Net-(U7-SW2)")
			(pinfunction "SW2")
			(pintype "power_out")
		)
		(pad "20" smd rect
			(at 1.4 -0.955)
			(size 1.3 0.2)
			(layers "F.Cu" "F.Mask" "F.Paste")
			(net 90 "+5V")
			(pinfunction "VIN2")
			(pintype "power_in")
		)
		(pad "21" smd rect
			(at 1.6 -1.405)
			(size 0.9 0.2)
			(layers "F.Cu" "F.Mask" "F.Paste")
			(net 272 "/Supply/SENSE3_P")
			(pinfunction "FB2")
			(pintype "input")
		)
		(pad "22" smd rect
			(at 1.125 -2.155 90)
			(size 0.8 0.2)
			(layers "F.Cu" "F.Mask" "F.Paste")
			(net 632 "Net-(U7-OUT2)")
			(pinfunction "OUT2")
			(pintype "power_out")
		)
		(pad "22" smd rect
			(at 1.29 -1.905 90)
			(size 0.3 0.525)
			(layers "F.Cu" "F.Mask" "F.Paste")
			(net 632 "Net-(U7-OUT2)")
			(pinfunction "OUT2")
			(pintype "power_out")
		)
		(pad "22" smd rect
			(at 1.54 -1.855)
			(size 1.025 0.2)
			(layers "F.Cu" "F.Mask" "F.Paste")
			(net 632 "Net-(U7-OUT2)")
			(pinfunction "OUT2")
			(pintype "power_out")
		)
		(pad "23" smd rect
			(at 0.675 -2.105 90)
			(size 0.9 0.2)
			(layers "F.Cu" "F.Mask" "F.Paste")
			(net 90 "+5V")
			(pinfunction "LSWI")
			(pintype "power_in")
		)
		(pad "24" smd rect
			(at 0.225 -2.105 90)
			(size 0.9 0.2)
			(layers "F.Cu" "F.Mask" "F.Paste")
			(net 229 "unconnected-(U7-LSWO-Pad24)")
			(pinfunction "LSWO")
			(pintype "power_out+no_connect")
		)
		(pad "25" smd rect
			(at -0.225 -2.105 90)
			(size 0.9 0.2)
			(layers "F.Cu" "F.Mask" "F.Paste")
			(net 417 "GND")
			(pinfunction "AGND")
			(pintype "power_in")
		)
		(pad "26" smd rect
			(at -0.675 -2.105 90)
			(size 0.9 0.2)
			(layers "F.Cu" "F.Mask" "F.Paste")
			(net 3 "Net-(U7-AVIN)")
			(pinfunction "AVIN")
			(pintype "input")
		)
	)
)
